# S9S_MB_2U (Grand Teton) — schematic netlist excerpt (pin names and nets, part order shuffled) for the footprints in the layout excerpt that follows; sources: Cadence DE-HDL packaged netlist, KiCad conversion of 03242023_DA0F0TMBIJ0_F0T_Motherboard_J_brd_V01_OCP.brd

R1752  Q_RES  33.2 1% CHIP  pkg 0402LF  page 222 : A = SGPIO_CLK_0 ; B = SGPIO_DEBUG_PLD_CLK
R3758  Q_RES  10 1% CHIP  pkg 0402LF  page 171 : A = P3V3_E1S_0_R ; B = VSENSE_P3V3_INA230_2_INP

(kicad_pcb
	(version 20260206)
	(generator "pcbnew")
	(generator_version "10.0")
	(general
		(thickness 1.6)
		(legacy_teardrops no)
	)
	(paper "A4")
	(title_block
		(title "03242023_DA0F0TMBIJ0_F0T_Motherboard_J_brd_V01_OCP.brd")
		(comment 1 "Grand Teton / footprints 2392-2393 of 6105")
	)
	(layers
		(0 "F.Cu" signal "TOP")
		(4 "In1.Cu" signal "GND")
		(6 "In2.Cu" signal "IN1")
		(8 "In3.Cu" signal "GND1")
		(10 "In4.Cu" signal "IN2")
		(12 "In5.Cu" signal "GND2")
		(14 "In6.Cu" signal "IN3")
		(16 "In7.Cu" signal "GND3")
		(18 "In8.Cu" signal "VCC")
		(20 "In9.Cu" signal "VCC1")
		(22 "In10.Cu" signal "GND4")
		(24 "In11.Cu" signal "IN4")
		(26 "In12.Cu" signal "GND5")
		(28 "In13.Cu" signal "IN5")
		(30 "In14.Cu" signal "GND6")
		(32 "In15.Cu" signal "IN6")
		(34 "In16.Cu" signal "GND7")
		(2 "B.Cu" signal "BOTTOM")
		(9 "F.Adhes" user "F.Adhesive")
		(11 "B.Adhes" user "B.Adhesive")
		(13 "F.Paste" user "Package Geometry/Pastemask Top")
		(15 "B.Paste" user "Package Geometry/Pastemask Bottom")
		(5 "F.SilkS" user "Ref Des/Silkscreen Top")
		(7 "B.SilkS" user "Ref Des/Silkscreen Bottom")
		(1 "F.Mask" user "Board Geometry/Soldermask Top")
		(3 "B.Mask" user "Board Geometry/Soldermask Bottom")
		(17 "Dwgs.User" user "User.Drawings")
		(19 "Cmts.User" user "User.Comments")
		(21 "Eco1.User" user "User.Eco1")
		(23 "Eco2.User" user "User.Eco2")
		(25 "Edge.Cuts" user "Board Geometry/Outline")
		(27 "Margin" user)
		(31 "F.CrtYd" user "Package Geometry/Place Bound Top")
		(29 "B.CrtYd" user "Package Geometry/Place Bound Bottom")
		(35 "F.Fab" user "Ref Des/Assembly Top")
		(33 "B.Fab" user "Ref Des/Assembly Bottom")
	)
	(footprint ""
		(layer "F.Cu")
		(at 220.190822 -57.851802 180)
		(property "Reference" "R3758"
			(at 0 0 180)
			(layer "F.SilkS")
			(hide yes)
			(effects
				(font
					(size 1.27 1.27)
				)
			)
		)
		(property "Value" ""
			(at 0 0 180)
			(layer "F.Fab")
			(effects
				(font
					(size 1.27 1.27)
				)
			)
		)
		(duplicate_pad_numbers_are_jumpers no)
		(fp_line
			(start 0.7874 0.4064)
			(end -0.7874 0.4064)
			(stroke
				(width 0.1524)
				(type default)
			)
			(layer "F.SilkS")
		)
		(fp_line
			(start 0.7874 -0.4064)
			(end 0.7874 0.4064)
			(stroke
				(width 0.1524)
				(type default)
			)
			(layer "F.SilkS")
		)
		(fp_line
			(start -0.7874 0.4064)
			(end -0.7874 -0.4064)
			(stroke
				(width 0.1524)
				(type default)
			)
			(layer "F.SilkS")
		)
		(fp_line
			(start -0.7874 -0.4064)
			(end 0.7874 -0.4064)
			(stroke
				(width 0.1524)
				(type default)
			)
			(layer "F.SilkS")
		)
		(fp_line
			(start 0.67945 0.3048)
			(end 0.120396 0.3048)
			(stroke
				(width 0.1)
				(type default)
			)
			(layer "F.Fab")
		)
		(fp_line
			(start 0.67945 -0.3048)
			(end 0.67945 0.3048)
			(stroke
				(width 0.1)
				(type default)
			)
			(layer "F.Fab")
		)
		(fp_line
			(start 0.12065 -0.2794)
			(end 0.12065 -0.3048)
			(stroke
				(width 0.1)
				(type default)
			)
			(layer "F.Fab")
		)
		(fp_line
			(start 0.12065 -0.3048)
			(end 0.67945 -0.3048)
			(stroke
				(width 0.1)
				(type default)
			)
			(layer "F.Fab")
		)
		(fp_line
			(start 0.120396 0.3048)
			(end 0.120396 0.2794)
			(stroke
				(width 0.1)
				(type default)
			)
			(layer "F.Fab")
		)
		(fp_line
			(start 0.120396 0.2794)
			(end -0.12065 0.2794)
			(stroke
				(width 0.1)
				(type default)
			)
			(layer "F.Fab")
		)
		(fp_line
			(start -0.12065 0.3048)
			(end -0.67945 0.3048)
			(stroke
				(width 0.1)
				(type default)
			)
			(layer "F.Fab")
		)
		(fp_line
			(start -0.12065 0.2794)
			(end -0.12065 0.3048)
			(stroke
				(width 0.1)
				(type default)
			)
			(layer "F.Fab")
		)
		(fp_line
			(start -0.12065 -0.2794)
			(end 0.12065 -0.2794)
			(stroke
				(width 0.1)
				(type default)
			)
			(layer "F.Fab")
		)
		(fp_line
			(start -0.12065 -0.305054)
			(end -0.12065 -0.2794)
			(stroke
				(width 0.1)
				(type default)
			)
			(layer "F.Fab")
		)
		(fp_line
			(start -0.67945 0.3048)
			(end -0.67945 -0.305054)
			(stroke
				(width 0.1)
				(type default)
			)
			(layer "F.Fab")
		)
		(fp_line
			(start -0.67945 -0.305054)
			(end -0.12065 -0.305054)
			(stroke
				(width 0.1)
				(type default)
			)
			(layer "F.Fab")
		)
		(pad "1" smd circle
			(at -0.40005 0 180)
			(size 0 0)
			(layers "F.Cu" "F.Mask" "F.Paste")
			(net "P3V3_E1S_0_R")
		)
		(pad "2" smd circle
			(at 0.40005 0 180)
			(size 0 0)
			(layers "F.Cu" "F.Mask" "F.Paste")
			(net "VSENSE_P3V3_INA230_2_INP")
		)
	)
	(footprint ""
		(layer "F.Cu")
		(at 157.988 -22.824948 90)
		(property "Reference" "R1752"
			(at 0 0 90)
			(layer "F.SilkS")
			(hide yes)
			(effects
				(font
					(size 1.27 1.27)
				)
			)
		)
		(property "Value" ""
			(at 0 0 90)
			(layer "F.Fab")
			(effects
				(font
					(size 1.27 1.27)
				)
			)
		)
		(duplicate_pad_numbers_are_jumpers no)
		(fp_line
			(start 0.7874 -0.4064)
			(end 0.7874 0.4064)
			(stroke
				(width 0.1524)
				(type default)
			)
			(layer "F.SilkS")
		)
		(fp_line
			(start -0.7874 -0.4064)
			(end 0.7874 -0.4064)
			(stroke
				(width 0.1524)
				(type default)
			)
			(layer "F.SilkS")
		)
		(fp_line
			(start 0.7874 0.4064)
			(end -0.7874 0.4064)
			(stroke
				(width 0.1524)
				(type default)
			)
			(layer "F.SilkS")
		)
		(fp_line
			(start -0.7874 0.4064)
			(end -0.7874 -0.4064)
			(stroke
				(width 0.1524)
				(type default)
			)
			(layer "F.SilkS")
		)
		(fp_line
			(start -0.12065 -0.305054)
			(end -0.12065 -0.2794)
			(stroke
				(width 0.1)
				(type default)
			)
			(layer "F.Fab")
		)
		(fp_line
			(start -0.67945 -0.305054)
			(end -0.12065 -0.305054)
			(stroke
				(width 0.1)
				(type default)
			)
			(layer "F.Fab")
		)
		(fp_line
			(start 0.67945 -0.3048)
			(end 0.67945 0.3048)
			(stroke
				(width 0.1)
				(type default)
			)
			(layer "F.Fab")
		)
		(fp_line
			(start 0.12065 -0.3048)
			(end 0.67945 -0.3048)
			(stroke
				(width 0.1)
				(type default)
			)
			(layer "F.Fab")
		)
		(fp_line
			(start 0.12065 -0.2794)
			(end 0.12065 -0.3048)
			(stroke
				(width 0.1)
				(type default)
			)
			(layer "F.Fab")
		)
		(fp_line
			(start -0.12065 -0.2794)
			(end 0.12065 -0.2794)
			(stroke
				(width 0.1)
				(type default)
			)
			(layer "F.Fab")
		)
		(fp_line
			(start 0.120396 0.2794)
			(end -0.12065 0.2794)
			(stroke
				(width 0.1)
				(type default)
			)
			(layer "F.Fab")
		)
		(fp_line
			(start -0.12065 0.2794)
			(end -0.12065 0.3048)
			(stroke
				(width 0.1)
				(type default)
			)
			(layer "F.Fab")
		)
		(fp_line
			(start 0.67945 0.3048)
			(end 0.120396 0.3048)
			(stroke
				(width 0.1)
				(type default)
			)
			(layer "F.Fab")
		)
		(fp_line
			(start 0.120396 0.3048)
			(end 0.120396 0.2794)
			(stroke
				(width 0.1)
				(type default)
			)
			(layer "F.Fab")
		)
		(fp_line
			(start -0.12065 0.3048)
			(end -0.67945 0.3048)
			(stroke
				(width 0.1)
				(type default)
			)
			(layer "F.Fab")
		)
		(fp_line
			(start -0.67945 0.3048)
			(end -0.67945 -0.305054)
			(stroke
				(width 0.1)
				(type default)
			)
			(layer "F.Fab")
		)
		(pad "1" smd circle
			(at -0.40005 0 90)
			(size 0 0)
			(layers "F.Cu" "F.Mask" "F.Paste")
			(net "SGPIO_CLK_0")
		)
		(pad "2" smd circle
			(at 0.40005 0 90)
			(size 0 0)
			(layers "F.Cu" "F.Mask" "F.Paste")
			(net "SGPIO_DEBUG_PLD_CLK")
		)
	)
)
